# T6G (Grand Teton) — schematic netlist excerpt (pin names and nets, part order shuffled) for the footprints in the layout excerpt that follows; sources: Cadence DE-HDL packaged netlist, KiCad conversion of 04192023_DAF0TMB3IC0_F0TG_MB_C_brd_V02_OCP.brd

R3440  Q_RES  0 5% EMPTY  pkg 0402LF  page 123 : A = GPU_BASE_ID0 ; B = GND

PL18  Q_INDUCTOR4P_14  150NH IND  pkg L_TLM117513Q-151QL_11X7-5XA  page 205
  \1\  = SW_PVDDIO_P0_SW2
  \2\  = IND_PVDDIO_P0_CPL3
  \3\  = IND_PVDDIO_P0_CPL2
  \4\  = PVDDIO_P0

(kicad_pcb
	(version 20260206)
	(generator "pcbnew")
	(generator_version "10.0")
	(general
		(thickness 1.6)
		(legacy_teardrops no)
	)
	(paper "A4")
	(title_block
		(title "04192023_DAF0TMB3IC0_F0TG_MB_C_brd_V02_OCP.brd")
		(comment 1 "Grand Teton / footprints 4822-4823 of 8354")
	)
	(layers
		(0 "F.Cu" signal "TOP")
		(4 "In1.Cu" signal "GND")
		(6 "In2.Cu" signal "IN1")
		(8 "In3.Cu" signal "GND1")
		(10 "In4.Cu" signal "IN2")
		(12 "In5.Cu" signal "GND2")
		(14 "In6.Cu" signal "IN3")
		(16 "In7.Cu" signal "GND3")
		(18 "In8.Cu" signal "VCC")
		(20 "In9.Cu" signal "VCC1")
		(22 "In10.Cu" signal "GND4")
		(24 "In11.Cu" signal "IN4")
		(26 "In12.Cu" signal "GND5")
		(28 "In13.Cu" signal "IN5")
		(30 "In14.Cu" signal "GND6")
		(32 "In15.Cu" signal "IN6")
		(34 "In16.Cu" signal "GND7")
		(2 "B.Cu" signal "BOTTOM")
		(9 "F.Adhes" user "F.Adhesive")
		(11 "B.Adhes" user "B.Adhesive")
		(13 "F.Paste" user "Package Geometry/Pastemask Top")
		(15 "B.Paste" user "Package Geometry/Pastemask Bottom")
		(5 "F.SilkS" user "Ref Des/Silkscreen Top")
		(7 "B.SilkS" user "Ref Des/Silkscreen Bottom")
		(1 "F.Mask" user "Board Geometry/Soldermask Top")
		(3 "B.Mask" user "Board Geometry/Soldermask Bottom")
		(17 "Dwgs.User" user "User.Drawings")
		(19 "Cmts.User" user "User.Comments")
		(21 "Eco1.User" user "User.Eco1")
		(23 "Eco2.User" user "User.Eco2")
		(25 "Edge.Cuts" user "Board Geometry/Outline")
		(27 "Margin" user)
		(31 "F.CrtYd" user "Package Geometry/Place Bound Top")
		(29 "B.CrtYd" user "Package Geometry/Place Bound Bottom")
		(35 "F.Fab" user "Ref Des/Assembly Top")
		(33 "B.Fab" user "Ref Des/Assembly Bottom")
	)
	(footprint ""
		(layer "F.Cu")
		(at 292.126162 -337.399122)
		(property "Reference" "PL18"
			(at -2.439162 -15.888208 0)
			(unlocked yes)
			(layer "F.SilkS")
			(effects
				(font
					(size 0.7874 0.5842)
					(thickness 0.1524)
				)
				(justify left)
			)
		)
		(property "Value" ""
			(at 0 0 0)
			(layer "F.Fab")
			(effects
				(font
					(size 1.27 1.27)
				)
			)
		)
		(duplicate_pad_numbers_are_jumpers no)
		(fp_line
			(start -3.750056 -5.500116)
			(end -2.393442 -5.500116)
			(stroke
				(width 0.1524)
				(type default)
			)
			(layer "F.SilkS")
		)
		(fp_line
			(start -3.750056 5.500116)
			(end -3.750056 -5.500116)
			(stroke
				(width 0.1524)
				(type default)
			)
			(layer "F.SilkS")
		)
		(fp_line
			(start -2.393442 5.500116)
			(end -3.750056 5.500116)
			(stroke
				(width 0.1524)
				(type default)
			)
			(layer "F.SilkS")
		)
		(fp_line
			(start 2.393442 5.500116)
			(end 3.750056 5.500116)
			(stroke
				(width 0.1524)
				(type default)
			)
			(layer "F.SilkS")
		)
		(fp_line
			(start 3.750056 -5.500116)
			(end 2.393442 -5.500116)
			(stroke
				(width 0.1524)
				(type default)
			)
			(layer "F.SilkS")
		)
		(fp_line
			(start 3.750056 5.500116)
			(end 3.750056 -5.500116)
			(stroke
				(width 0.1524)
				(type default)
			)
			(layer "F.SilkS")
		)
		(fp_poly
			(pts
				(xy -3.9116 -4.249928) (xy -4.3434 -4.034028) (xy -4.3434 -4.465828)
			)
			(stroke
				(width 0)
				(type default)
			)
			(fill yes)
			(layer "F.SilkS")
		)
		(fp_line
			(start -3.750056 -5.500116)
			(end -3.750056 5.500116)
			(stroke
				(width 0.1)
				(type default)
			)
			(layer "F.Fab")
		)
		(fp_line
			(start -3.750056 5.500116)
			(end 3.750056 5.500116)
			(stroke
				(width 0.1)
				(type default)
			)
			(layer "F.Fab")
		)
		(fp_line
			(start 3.750056 -5.500116)
			(end -3.750056 -5.500116)
			(stroke
				(width 0.1)
				(type default)
			)
			(layer "F.Fab")
		)
		(fp_line
			(start 3.750056 5.500116)
			(end 3.750056 -5.500116)
			(stroke
				(width 0.1)
				(type default)
			)
			(layer "F.Fab")
		)
		(fp_poly
			(pts
				(xy -4.9276 -4.757928) (xy -4.9276 -3.741928) (xy -3.9116 -4.249928)
			)
			(stroke
				(width 0)
				(type default)
			)
			(fill yes)
			(layer "F.Fab")
		)
		(pad "1" smd rect
			(at 0 -4.249928 270)
			(size 2.413 4.5212)
			(layers "F.Cu" "F.Mask" "F.Paste")
			(net "SW_PVDDIO_P0_SW2")
		)
		(pad "2" smd rect
			(at 0 -1.175004 270)
			(size 1.3716 4.5212)
			(layers "F.Cu" "F.Mask" "F.Paste")
			(net "IND_PVDDIO_P0_CPL3")
		)
		(pad "3" smd rect
			(at 0 1.175004 270)
			(size 1.3716 4.5212)
			(layers "F.Cu" "F.Mask" "F.Paste")
			(net "IND_PVDDIO_P0_CPL2")
		)
		(pad "4" smd rect
			(at 0 4.249928 270)
			(size 2.413 4.5212)
			(layers "F.Cu" "F.Mask" "F.Paste")
			(net "PVDDIO_P0")
		)
	)
	(footprint ""
		(layer "F.Cu")
		(at 188.296804 -428.069248 90)
		(property "Reference" "R3440"
			(at 0 0 90)
			(layer "F.SilkS")
			(hide yes)
			(effects
				(font
					(size 1.27 1.27)
				)
			)
		)
		(property "Value" ""
			(at 0 0 90)
			(layer "F.Fab")
			(effects
				(font
					(size 1.27 1.27)
				)
			)
		)
		(duplicate_pad_numbers_are_jumpers no)
		(fp_line
			(start 0.7874 -0.4064)
			(end 0.7874 0.4064)
			(stroke
				(width 0.1524)
				(type default)
			)
			(layer "F.SilkS")
		)
		(fp_line
			(start -0.7874 -0.4064)
			(end 0.7874 -0.4064)
			(stroke
				(width 0.1524)
				(type default)
			)
			(layer "F.SilkS")
		)
		(fp_line
			(start 0.7874 0.4064)
			(end -0.7874 0.4064)
			(stroke
				(width 0.1524)
				(type default)
			)
			(layer "F.SilkS")
		)
		(fp_line
			(start -0.7874 0.4064)
			(end -0.7874 -0.4064)
			(stroke
				(width 0.1524)
				(type default)
			)
			(layer "F.SilkS")
		)
		(fp_line
			(start -0.12065 -0.305054)
			(end -0.12065 -0.2794)
			(stroke
				(width 0.1)
				(type default)
			)
			(layer "F.Fab")
		)
		(fp_line
			(start -0.67945 -0.305054)
			(end -0.12065 -0.305054)
			(stroke
				(width 0.1)
				(type default)
			)
			(layer "F.Fab")
		)
		(fp_line
			(start 0.67945 -0.3048)
			(end 0.67945 0.3048)
			(stroke
				(width 0.1)
				(type default)
			)
			(layer "F.Fab")
		)
		(fp_line
			(start 0.12065 -0.3048)
			(end 0.67945 -0.3048)
			(stroke
				(width 0.1)
				(type default)
			)
			(layer "F.Fab")
		)
		(fp_line
			(start 0.12065 -0.2794)
			(end 0.12065 -0.3048)
			(stroke
				(width 0.1)
				(type default)
			)
			(layer "F.Fab")
		)
		(fp_line
			(start -0.12065 -0.2794)
			(end 0.12065 -0.2794)
			(stroke
				(width 0.1)
				(type default)
			)
			(layer "F.Fab")
		)
		(fp_line
			(start 0.120396 0.2794)
			(end -0.12065 0.2794)
			(stroke
				(width 0.1)
				(type default)
			)
			(layer "F.Fab")
		)
		(fp_line
			(start -0.12065 0.2794)
			(end -0.12065 0.3048)
			(stroke
				(width 0.1)
				(type default)
			)
			(layer "F.Fab")
		)
		(fp_line
			(start 0.67945 0.3048)
			(end 0.120396 0.3048)
			(stroke
				(width 0.1)
				(type default)
			)
			(layer "F.Fab")
		)
		(fp_line
			(start 0.120396 0.3048)
			(end 0.120396 0.2794)
			(stroke
				(width 0.1)
				(type default)
			)
			(layer "F.Fab")
		)
		(fp_line
			(start -0.12065 0.3048)
			(end -0.67945 0.3048)
			(stroke
				(width 0.1)
				(type default)
			)
			(layer "F.Fab")
		)
		(fp_line
			(start -0.67945 0.3048)
			(end -0.67945 -0.305054)
			(stroke
				(width 0.1)
				(type default)
			)
			(layer "F.Fab")
		)
		(pad "1" smd circle
			(at -0.40005 0 90)
			(size 0 0)
			(layers "F.Cu" "F.Mask" "F.Paste")
			(net "GPU_BASE_ID0")
		)
		(pad "2" smd circle
			(at 0.40005 0 90)
			(size 0 0)
			(layers "F.Cu" "F.Mask" "F.Paste")
			(net "GND")
		)
	)
)
